(kicad_pcb
	(version 20240108)
	(generator "pcbnew")
	(generator_version "8.0")
	(general
		(thickness 1.6)
		(legacy_teardrops no)
	)
	(paper "A4")
	(title_block
		(title "Jetson Orin Baseboard OCuLink Expansion")
		(date "2025-03-18")
		(rev "1.1.0")
		(company "Antmicro Ltd")
		(comment 1 "www.antmicro.com")
		(comment 9 "footprints 27-27 of 119")
	)
	(layers
		(0 "F.Cu" signal)
		(1 "In1.Cu" signal)
		(2 "In2.Cu" signal)
		(31 "B.Cu" signal)
		(32 "B.Adhes" user "B.Adhesive")
		(33 "F.Adhes" user "F.Adhesive")
		(34 "B.Paste" user)
		(35 "F.Paste" user)
		(36 "B.SilkS" user "B.Silkscreen")
		(37 "F.SilkS" user "F.Silkscreen")
		(38 "B.Mask" user)
		(39 "F.Mask" user)
		(40 "Dwgs.User" user "User.Drawings")
		(41 "Cmts.User" user "User.Comments")
		(42 "Eco1.User" user "User.Eco1")
		(43 "Eco2.User" user "User.Eco2")
		(44 "Edge.Cuts" user)
		(45 "Margin" user)
		(46 "B.CrtYd" user "B.Courtyard")
		(47 "F.CrtYd" user "F.Courtyard")
		(48 "B.Fab" user)
		(49 "F.Fab" user)
	)
	(footprint "antmicro-footprints:C_0402_1005Metric"
		(layer "F.Cu")
		(at 129.2 108.32 180)
		(descr "Capacitor SMD 0402")
		(tags "capacitor SMD 0402")
		(property "Reference" "C42"
			(at 0.9 0.37 0)
			(layer "F.SilkS")
			(effects
				(font
					(size 0.7 0.7)
					(thickness 0.15)
				)
				(justify right top)
			)
		)
		(property "Value" "C_220n_0402"
			(at -1.022927 2.155213 0)
			(layer "F.Fab")
			(effects
				(font
					(size 0.7 0.7)
					(thickness 0.15)
				)
				(justify right top)
			)
		)
		(property "Footprint" "antmicro-footprints:C_0402_1005Metric"
			(at 0 0 0)
			(layer "F.Fab")
			(hide yes)
			(effects
				(font
					(size 1.27 1.27)
					(thickness 0.15)
				)
			)
		)
		(property "Datasheet" "https://www.yageo.com/en/Chart/Download/pdf/CC0402KRX5R6BB224"
			(at 0 0 0)
			(layer "F.Fab")
			(hide yes)
			(effects
				(font
					(size 1.27 1.27)
					(thickness 0.15)
				)
			)
		)
		(property "Description" "SMD Multilayer Ceramic Capacitor, 0.22 µF, 10 V, 0402 [1005 Metric], ± 10%, X5R, CC Series"
			(at 0 0 0)
			(layer "F.Fab")
			(hide yes)
			(effects
				(font
					(size 1.27 1.27)
					(thickness 0.15)
				)
			)
		)
		(property "MPN" "CC0402KRX5R6BB224"
			(at 0 0 180)
			(unlocked yes)
			(layer "F.Fab")
			(hide yes)
			(effects
				(font
					(size 1 1)
					(thickness 0.15)
				)
			)
		)
		(property "Manufacturer" "YAGEO"
			(at 0 0 180)
			(unlocked yes)
			(layer "F.Fab")
			(hide yes)
			(effects
				(font
					(size 1 1)
					(thickness 0.15)
				)
			)
		)
		(property "License" "Apache-2.0"
			(at 0 0 180)
			(unlocked yes)
			(layer "F.Fab")
			(hide yes)
			(effects
				(font
					(size 1 1)
					(thickness 0.15)
				)
			)
		)
		(property "Author" "Antmicro"
			(at 0 0 180)
			(unlocked yes)
			(layer "F.Fab")
			(hide yes)
			(effects
				(font
					(size 1 1)
					(thickness 0.15)
				)
			)
		)
		(property "Val" "220n"
			(at 0 0 180)
			(unlocked yes)
			(layer "F.Fab")
			(hide yes)
			(effects
				(font
					(size 1 1)
					(thickness 0.15)
				)
			)
		)
		(property "Voltage" ""
			(at 0 0 180)
			(unlocked yes)
			(layer "F.Fab")
			(hide yes)
			(effects
				(font
					(size 1 1)
					(thickness 0.15)
				)
			)
		)
		(property "Dielectric" ""
			(at 0 0 180)
			(unlocked yes)
			(layer "F.Fab")
			(hide yes)
			(effects
				(font
					(size 1 1)
					(thickness 0.15)
				)
			)
		)
		(property "Public" "False"
			(at 0 0 180)
			(unlocked yes)
			(layer "F.Fab")
			(hide yes)
			(effects
				(font
					(size 1 1)
					(thickness 0.15)
				)
			)
		)
		(sheetname "Root")
		(sheetfile "jetson-orin-baseboard-oculink-expansion.kicad_sch")
		(attr smd)
		(fp_rect
			(start -0.925 -0.47)
			(end 0.925 0.47)
			(stroke
				(width 0.05)
				(type default)
			)
			(fill none)
			(layer "F.CrtYd")
		)
		(fp_line
			(start 0.504 0.248)
			(end -0.494 0.248)
			(stroke
				(width 0.15)
				(type solid)
			)
			(layer "F.Fab")
		)
		(fp_line
			(start 0.504 -0.25)
			(end 0.504 0.248)
			(stroke
				(width 0.15)
				(type solid)
			)
			(layer "F.Fab")
		)
		(fp_line
			(start -0.494 0.248)
			(end -0.494 -0.25)
			(stroke
				(width 0.15)
				(type solid)
			)
			(layer "F.Fab")
		)
		(fp_line
			(start -0.494 -0.25)
			(end 0.504 -0.25)
			(stroke
				(width 0.15)
				(type solid)
			)
			(layer "F.Fab")
		)
		(fp_text user "${REFERENCE}"
			(at -0.939 4.599 0)
			(layer "F.Fab")
			(hide yes)
			(effects
				(font
					(size 0.7 0.7)
					(thickness 0.15)
				)
				(justify right top)
			)
		)
		(fp_text user "Author: Antmicro"
			(at -0.939 3.399 0)
			(layer "F.Fab")
			(hide yes)
			(effects
				(font
					(size 0.7 0.7)
					(thickness 0.15)
				)
				(justify right top)
			)
		)
		(fp_text user "License: Apache-2.0"
			(at -0.939 5.799 0)
			(layer "F.Fab")
			(hide yes)
			(effects
				(font
					(size 0.7 0.7)
					(thickness 0.15)
				)
				(justify right top)
			)
		)
		(pad "1" smd roundrect
			(at -0.48 0 180)
			(size 0.59 0.64)
			(layers "F.Cu" "F.Paste" "F.Mask")
			(roundrect_rratio 0.25)
			(net 74 "/PCIE_{I}_RX0-")
			(pintype "passive")
		)
		(pad "2" smd roundrect
			(at 0.48 0 180)
			(size 0.59 0.64)
			(layers "F.Cu" "F.Paste" "F.Mask")
			(roundrect_rratio 0.25)
			(net 73 "/PCIE_{I}_C.RX0-")
			(pintype "passive")
		)
	)
)
